# S9S_MB_2U (Grand Teton) — schematic netlist excerpt (pin names and nets, part order shuffled) for the footprints in the layout excerpt that follows; sources: Cadence DE-HDL packaged netlist, KiCad conversion of 03242023_DA0F0TMBIJ0_F0T_Motherboard_J_brd_V01_OCP.brd

U328  DS125BR111RTWR  EMPTY  pkg WQFN24_TH_0-5_4X4XA  page 167
  \eqb0||ad3\  = FM_P2E_BUF2_EQB0
  \eqb1||ad2\  = FM_P2E_BUF2_EQB1
  ENSMB  = PD_P2E_BUF2_ENSMB
  \sda||voda_db\  = FM_P2E_BUF2_VODA_DB
  \scl||vodb_db\  = FM_P2E_BUF2_VODB_DB
  PWDN  = FM_P2E_EN2_N
  \outa+\  = P2E_MB_BMC_TX_BUF2_DP<0>
  \outa-\  = P2E_MB_BMC_TX_BUF2_DN<0>
  \eqa1||ad1\  = FM_P2E_BUF2_EQA1
  \eqa0||ad0\  = FM_P2E_BUF2_EQA0
  \inb+\  = P2E_MB_BMC_RX_R2_DP<0>
  \inb-\  = P2E_MB_BMC_RX_R2_DN<0>
  RES  = NC_RES
  SD_TH  = FM_P2E_BUF2_SD_TH
  VIN  = P3V3_AUX
  VDD_SEL  = GND
  \vod_sel||readen#\  = FM_P2E_BUF2_VOD_SEL
  \rxdet||done#\  = FM_P2E_BUF2_RXDET
  \outb-\  = P2E_MB_BMC_RX_BUF2_C_DN<0>
  \outb+\  = P2E_MB_BMC_RX_BUF2_C_DP<0>
  VDD_21  = P2E_BUF2_VDD
  VDD_22  = P2E_BUF2_VDD
  \ina-\  = P2E_MB_BMC_TX_C_R2_DN<0>
  \ina+\  = P2E_MB_BMC_TX_C_R2_DP<0>
  TH_GND  = GND

(kicad_pcb
	(version 20260206)
	(generator "pcbnew")
	(generator_version "10.0")
	(general
		(thickness 1.6)
		(legacy_teardrops no)
	)
	(paper "A4")
	(title_block
		(title "03242023_DA0F0TMBIJ0_F0T_Motherboard_J_brd_V01_OCP.brd")
		(comment 1 "Grand Teton / footprints 3239-3239 of 6105")
	)
	(layers
		(0 "F.Cu" signal "TOP")
		(4 "In1.Cu" signal "GND")
		(6 "In2.Cu" signal "IN1")
		(8 "In3.Cu" signal "GND1")
		(10 "In4.Cu" signal "IN2")
		(12 "In5.Cu" signal "GND2")
		(14 "In6.Cu" signal "IN3")
		(16 "In7.Cu" signal "GND3")
		(18 "In8.Cu" signal "VCC")
		(20 "In9.Cu" signal "VCC1")
		(22 "In10.Cu" signal "GND4")
		(24 "In11.Cu" signal "IN4")
		(26 "In12.Cu" signal "GND5")
		(28 "In13.Cu" signal "IN5")
		(30 "In14.Cu" signal "GND6")
		(32 "In15.Cu" signal "IN6")
		(34 "In16.Cu" signal "GND7")
		(2 "B.Cu" signal "BOTTOM")
		(9 "F.Adhes" user "F.Adhesive")
		(11 "B.Adhes" user "B.Adhesive")
		(13 "F.Paste" user "Package Geometry/Pastemask Top")
		(15 "B.Paste" user "Package Geometry/Pastemask Bottom")
		(5 "F.SilkS" user "Ref Des/Silkscreen Top")
		(7 "B.SilkS" user "Ref Des/Silkscreen Bottom")
		(1 "F.Mask" user "Board Geometry/Soldermask Top")
		(3 "B.Mask" user "Board Geometry/Soldermask Bottom")
		(17 "Dwgs.User" user "User.Drawings")
		(19 "Cmts.User" user "User.Comments")
		(21 "Eco1.User" user "User.Eco1")
		(23 "Eco2.User" user "User.Eco2")
		(25 "Edge.Cuts" user "Board Geometry/Outline")
		(27 "Margin" user)
		(31 "F.CrtYd" user "Package Geometry/Place Bound Top")
		(29 "B.CrtYd" user "Package Geometry/Place Bound Bottom")
		(35 "F.Fab" user "Ref Des/Assembly Top")
		(33 "B.Fab" user "Ref Des/Assembly Bottom")
	)
	(footprint ""
		(layer "F.Cu")
		(at 39.960042 -392.430254 180)
		(property "Reference" "U328"
			(at 6.072124 -4.195318 0)
			(unlocked yes)
			(layer "F.SilkS")
			(effects
				(font
					(size 0.7874 0.5842)
					(thickness 0.1524)
				)
				(justify left)
			)
		)
		(property "Value" ""
			(at 0 0 180)
			(layer "F.Fab")
			(effects
				(font
					(size 1.27 1.27)
				)
			)
		)
		(duplicate_pad_numbers_are_jumpers no)
		(fp_line
			(start 2.050034 2.050034)
			(end 1.524 2.050034)
			(stroke
				(width 0.1524)
				(type default)
			)
			(layer "F.SilkS")
		)
		(fp_line
			(start 2.050034 1.524)
			(end 2.050034 2.050034)
			(stroke
				(width 0.1524)
				(type default)
			)
			(layer "F.SilkS")
		)
		(fp_line
			(start 2.050034 -2.050034)
			(end 2.050034 -1.524)
			(stroke
				(width 0.1524)
				(type default)
			)
			(layer "F.SilkS")
		)
		(fp_line
			(start 1.524 -2.050034)
			(end 2.050034 -2.050034)
			(stroke
				(width 0.1524)
				(type default)
			)
			(layer "F.SilkS")
		)
		(fp_line
			(start -1.524 2.050034)
			(end -2.050034 2.050034)
			(stroke
				(width 0.1524)
				(type default)
			)
			(layer "F.SilkS")
		)
		(fp_line
			(start -2.050034 2.050034)
			(end -2.050034 1.524)
			(stroke
				(width 0.1524)
				(type default)
			)
			(layer "F.SilkS")
		)
		(fp_line
			(start -2.050034 -1.524)
			(end -2.050034 -2.050034)
			(stroke
				(width 0.1524)
				(type default)
			)
			(layer "F.SilkS")
		)
		(fp_line
			(start -2.050034 -2.050034)
			(end -1.524 -2.050034)
			(stroke
				(width 0.1524)
				(type default)
			)
			(layer "F.SilkS")
		)
		(fp_poly
			(pts
				(xy -2.634234 -1.542034) (xy -2.050034 -1.542034) (xy -2.050034 -2.126234) (xy -2.634234 -2.126234)
			)
			(stroke
				(width 0)
				(type default)
			)
			(fill yes)
			(layer "F.SilkS")
		)
		(fp_line
			(start 2.050034 2.050034)
			(end -2.050034 2.050034)
			(stroke
				(width 0.1)
				(type default)
			)
			(layer "F.Fab")
		)
		(fp_line
			(start 2.050034 -2.050034)
			(end 2.050034 2.050034)
			(stroke
				(width 0.1)
				(type default)
			)
			(layer "F.Fab")
		)
		(fp_line
			(start -2.050034 2.050034)
			(end -2.050034 -2.050034)
			(stroke
				(width 0.1)
				(type default)
			)
			(layer "F.Fab")
		)
		(fp_line
			(start -2.050034 -2.050034)
			(end 2.050034 -2.050034)
			(stroke
				(width 0.1)
				(type default)
			)
			(layer "F.Fab")
		)
		(fp_poly
			(pts
				(xy -2.634234 -1.542034) (xy -2.050034 -1.542034) (xy -2.050034 -2.126234) (xy -2.634234 -2.126234)
			)
			(stroke
				(width 0)
				(type default)
			)
			(fill yes)
			(layer "F.Fab")
		)
		(pad "1" smd circle
			(at -1.89992 -1.249934 90)
			(size 0 0)
			(layers "F.Cu" "F.Mask" "F.Paste")
			(net "FM_P2E_BUF2_EQB0")
		)
		(pad "2" smd circle
			(at -1.89992 -0.750062 90)
			(size 0 0)
			(layers "F.Cu" "F.Mask" "F.Paste")
			(net "FM_P2E_BUF2_EQB1")
		)
		(pad "3" smd circle
			(at -1.89992 -0.249936 90)
			(size 0 0)
			(layers "F.Cu" "F.Mask" "F.Paste")
			(net "PD_P2E_BUF2_ENSMB")
		)
		(pad "4" smd circle
			(at -1.89992 0.249936 90)
			(size 0 0)
			(layers "F.Cu" "F.Mask" "F.Paste")
			(net "FM_P2E_BUF2_VODA_DB")
		)
		(pad "5" smd circle
			(at -1.89992 0.750062 90)
			(size 0 0)
			(layers "F.Cu" "F.Mask" "F.Paste")
			(net "FM_P2E_BUF2_VODB_DB")
		)
		(pad "6" smd circle
			(at -1.89992 1.249934 90)
			(size 0 0)
			(layers "F.Cu" "F.Mask" "F.Paste")
			(net "FM_P2E_EN2_N")
		)
		(pad "7" smd circle
			(at -1.249934 1.89992 180)
			(size 0 0)
			(layers "F.Cu" "F.Mask" "F.Paste")
			(net "P2E_MB_BMC_TX_BUF2_DP<0>")
		)
		(pad "8" smd circle
			(at -0.750062 1.89992 180)
			(size 0 0)
			(layers "F.Cu" "F.Mask" "F.Paste")
			(net "P2E_MB_BMC_TX_BUF2_DN<0>")
		)
		(pad "9" smd circle
			(at -0.249936 1.89992 180)
			(size 0 0)
			(layers "F.Cu" "F.Mask" "F.Paste")
			(net "FM_P2E_BUF2_EQA1")
		)
		(pad "10" smd circle
			(at 0.249936 1.89992 180)
			(size 0 0)
			(layers "F.Cu" "F.Mask" "F.Paste")
			(net "FM_P2E_BUF2_EQA0")
		)
		(pad "11" smd circle
			(at 0.750062 1.89992 180)
			(size 0 0)
			(layers "F.Cu" "F.Mask" "F.Paste")
			(net "P2E_MB_BMC_RX_R2_DP<0>")
		)
		(pad "12" smd circle
			(at 1.249934 1.89992 180)
			(size 0 0)
			(layers "F.Cu" "F.Mask" "F.Paste")
			(net "P2E_MB_BMC_RX_R2_DN<0>")
		)
		(pad "13" smd circle
			(at 1.89992 1.249934 90)
			(size 0 0)
			(layers "F.Cu" "F.Mask" "F.Paste")
			(net "NC_RES")
		)
		(pad "14" smd circle
			(at 1.89992 0.750062 90)
			(size 0 0)
			(layers "F.Cu" "F.Mask" "F.Paste")
			(net "FM_P2E_BUF2_SD_TH")
		)
		(pad "15" smd circle
			(at 1.89992 0.249936 90)
			(size 0 0)
			(layers "F.Cu" "F.Mask" "F.Paste")
			(net "P3V3_AUX")
		)
		(pad "16" smd circle
			(at 1.89992 -0.249936 90)
			(size 0 0)
			(layers "F.Cu" "F.Mask" "F.Paste")
			(net "GND")
		)
		(pad "17" smd circle
			(at 1.89992 -0.750062 90)
			(size 0 0)
			(layers "F.Cu" "F.Mask" "F.Paste")
			(net "FM_P2E_BUF2_VOD_SEL")
		)
		(pad "18" smd circle
			(at 1.89992 -1.249934 90)
			(size 0 0)
			(layers "F.Cu" "F.Mask" "F.Paste")
			(net "FM_P2E_BUF2_RXDET")
		)
		(pad "19" smd circle
			(at 1.249934 -1.89992 180)
			(size 0 0)
			(layers "F.Cu" "F.Mask" "F.Paste")
			(net "P2E_MB_BMC_RX_BUF2_C_DN<0>")
		)
		(pad "20" smd circle
			(at 0.750062 -1.89992 180)
			(size 0 0)
			(layers "F.Cu" "F.Mask" "F.Paste")
			(net "P2E_MB_BMC_RX_BUF2_C_DP<0>")
		)
		(pad "21" smd circle
			(at 0.249936 -1.89992 180)
			(size 0 0)
			(layers "F.Cu" "F.Mask" "F.Paste")
			(net "P2E_BUF2_VDD")
		)
		(pad "22" smd circle
			(at -0.249936 -1.89992 180)
			(size 0 0)
			(layers "F.Cu" "F.Mask" "F.Paste")
			(net "P2E_BUF2_VDD")
		)
		(pad "23" smd circle
			(at -0.750062 -1.89992 180)
			(size 0 0)
			(layers "F.Cu" "F.Mask" "F.Paste")
			(net "P2E_MB_BMC_TX_C_R2_DN<0>")
		)
		(pad "24" smd circle
			(at -1.249934 -1.89992 180)
			(size 0 0)
			(layers "F.Cu" "F.Mask" "F.Paste")
			(net "P2E_MB_BMC_TX_C_R2_DP<0>")
		)
		(pad "25" smd circle
			(at 0 0 180)
			(size 0 0)
			(layers "F.Cu" "F.Mask" "F.Paste")
			(net "GND")
		)
	)
)
